(kicad_pcb
	(version 20260206)
	(generator "pcbnew")
	(generator_version "10.0")
	(general
		(thickness 1.6)
		(legacy_teardrops no)
	)
	(paper "A4")
	(title_block
		(title "fcb — 12433-1M.1206WZS1330.brd")
		(comment 1 "Open Vault / Knox (Wiwynn) / footprints 99-105 of 495")
	)
	(layers
		(0 "F.Cu" signal "TOP")
		(4 "In1.Cu" signal "L2GND")
		(6 "In2.Cu" signal "L3VCC")
		(2 "B.Cu" signal "BOTTOM")
		(9 "F.Adhes" user "F.Adhesive")
		(11 "B.Adhes" user "B.Adhesive")
		(13 "F.Paste" user "Package Geometry/Pastemask Top")
		(15 "B.Paste" user "Package Geometry/Pastemask Bottom")
		(5 "F.SilkS" user "Ref Des/Silkscreen Top")
		(7 "B.SilkS" user "Ref Des/Silkscreen Bottom")
		(1 "F.Mask" user "Board Geometry/Soldermask Top")
		(3 "B.Mask" user "Board Geometry/Soldermask Bottom")
		(17 "Dwgs.User" user "User.Drawings")
		(19 "Cmts.User" user "User.Comments")
		(21 "Eco1.User" user "User.Eco1")
		(23 "Eco2.User" user "User.Eco2")
		(25 "Edge.Cuts" user "Board Geometry/Outline")
		(27 "Margin" user)
		(31 "F.CrtYd" user "Package Geometry/Place Bound Top")
		(29 "B.CrtYd" user "Package Geometry/Place Bound Bottom")
		(35 "F.Fab" user "Ref Des/Assembly Top")
		(33 "B.Fab" user "Ref Des/Assembly Bottom")
	)
	(footprint ""
		(layer "F.Cu")
		(at 24.384 -237.871)
		(property "Reference" "PC43"
			(at 0 0 0)
			(layer "F.SilkS")
			(hide yes)
			(effects
				(font
					(size 1.27 1.27)
				)
			)
		)
		(property "Value" "SC22U16V6MX-GP"
			(at -0.0762 -5.1308 0)
			(unlocked yes)
			(layer "F.Fab")
			(hide yes)
			(effects
				(font
					(size 1.016 1.016)
					(thickness 0.1524)
				)
			)
		)
		(property "Device Type" "C1206H71"
			(at -0.127 -6.6548 0)
			(unlocked yes)
			(layer "F.Fab")
			(hide yes)
			(effects
				(font
					(size 1.016 1.016)
					(thickness 0.1524)
				)
			)
		)
		(duplicate_pad_numbers_are_jumpers no)
		(fp_line
			(start -1.016 -2.2352)
			(end 1.016 -2.2352)
			(stroke
				(width 0.1524)
				(type default)
			)
			(layer "F.SilkS")
		)
		(fp_line
			(start -1.016 -0.8382)
			(end -1.016 -2.2352)
			(stroke
				(width 0.1524)
				(type default)
			)
			(layer "F.SilkS")
		)
		(fp_line
			(start -1.016 2.2352)
			(end -1.016 0.8382)
			(stroke
				(width 0.1524)
				(type default)
			)
			(layer "F.SilkS")
		)
		(fp_line
			(start 1.016 -2.2352)
			(end 1.016 -0.8382)
			(stroke
				(width 0.1524)
				(type default)
			)
			(layer "F.SilkS")
		)
		(fp_line
			(start 1.016 0.8382)
			(end 1.016 2.2352)
			(stroke
				(width 0.1524)
				(type default)
			)
			(layer "F.SilkS")
		)
		(fp_line
			(start 1.016 2.2352)
			(end -1.016 2.2352)
			(stroke
				(width 0.1524)
				(type default)
			)
			(layer "F.SilkS")
		)
		(fp_rect
			(start -1.0922 2.3114)
			(end 1.0922 -2.3114)
			(stroke
				(width 0)
				(type default)
			)
			(fill no)
			(layer "F.CrtYd")
		)
		(fp_poly
			(pts
				(xy 1.0922 -2.3114) (xy 1.0922 2.3114) (xy -1.0922 2.3114) (xy -1.0922 -2.3114)
			)
			(stroke
				(width 0)
				(type default)
			)
			(fill no)
			(layer "F.Fab")
		)
		(pad "1" smd rect
			(at 0 -1.397)
			(size 1.651 1.27)
			(layers "F.Cu" "F.Mask" "F.Paste")
			(net "P3V3_LX_COPPER")
		)
		(pad "2" smd rect
			(at 0 1.397)
			(size 1.651 1.27)
			(layers "F.Cu" "F.Mask" "F.Paste")
			(net "GND")
		)
	)
	(footprint ""
		(layer "F.Cu")
		(at 33.91789 -167.723566 180)
		(property "Reference" "R11"
			(at 0 0 180)
			(layer "F.SilkS")
			(hide yes)
			(effects
				(font
					(size 1.27 1.27)
				)
			)
		)
		(property "Value" "100KR2J-1-GP"
			(at 0.064008 -3.993896 180)
			(unlocked yes)
			(layer "F.Fab")
			(hide yes)
			(effects
				(font
					(size 1.016 1.016)
					(thickness 0.1524)
				)
			)
		)
		(property "Device Type" "R402H16"
			(at 0.064008 -5.517896 180)
			(unlocked yes)
			(layer "F.Fab")
			(hide yes)
			(effects
				(font
					(size 1.016 1.016)
					(thickness 0.1524)
				)
			)
		)
		(duplicate_pad_numbers_are_jumpers no)
		(fp_line
			(start 0.508 -0.9398)
			(end -0.508 -0.9398)
			(stroke
				(width 0.1524)
				(type default)
			)
			(layer "F.SilkS")
		)
		(fp_line
			(start -0.508 -0.9398)
			(end -0.508 0.9398)
			(stroke
				(width 0.1524)
				(type default)
			)
			(layer "F.SilkS")
		)
		(fp_rect
			(start -0.508 0.9398)
			(end 0.508 -0.9398)
			(stroke
				(width 0)
				(type default)
			)
			(fill no)
			(layer "F.CrtYd")
		)
		(fp_rect
			(start -0.508 0.9398)
			(end 0.508 -0.9398)
			(stroke
				(width 0)
				(type default)
			)
			(fill no)
			(layer "F.Fab")
		)
		(pad "1" smd custom
			(at 0 -0.4445 180)
			(size 0.1397 0.1397)
			(layers "F.Cu" "F.Mask" "F.Paste")
			(net "NCT7904_ADR")
			(options
				(clearance outline)
				(anchor circle)
			)
			(primitives
				(gr_poly
					(pts
						(arc
							(start -0.1778 -0.2794)
							(mid -0.249642 -0.249642)
							(end -0.2794 -0.1778)
						)
						(arc
							(start -0.2794 0.1778)
							(mid -0.249642 0.249642)
							(end -0.1778 0.2794)
						)
						(arc
							(start 0.1778 0.2794)
							(mid 0.249642 0.249642)
							(end 0.2794 0.1778)
						)
						(arc
							(start 0.2794 -0.1778)
							(mid 0.249642 -0.249642)
							(end 0.1778 -0.2794)
						)
					)
					(width 0)
					(fill yes)
				)
			)
		)
		(pad "2" smd custom
			(at 0 0.4445 180)
			(size 0.1397 0.1397)
			(layers "F.Cu" "F.Mask" "F.Paste")
			(net "GND")
			(options
				(clearance outline)
				(anchor circle)
			)
			(primitives
				(gr_poly
					(pts
						(arc
							(start -0.1778 -0.2794)
							(mid -0.249642 -0.249642)
							(end -0.2794 -0.1778)
						)
						(arc
							(start -0.2794 0.1778)
							(mid -0.249642 0.249642)
							(end -0.1778 0.2794)
						)
						(arc
							(start 0.1778 0.2794)
							(mid 0.249642 0.249642)
							(end 0.2794 0.1778)
						)
						(arc
							(start 0.2794 -0.1778)
							(mid 0.249642 -0.249642)
							(end 0.1778 -0.2794)
						)
					)
					(width 0)
					(fill yes)
				)
			)
		)
	)
	(footprint ""
		(layer "F.Cu")
		(at 22.352 -188.0616 90)
		(property "Reference" "D6"
			(at 0 0 90)
			(layer "F.SilkS")
			(hide yes)
			(effects
				(font
					(size 1.27 1.27)
				)
			)
		)
		(property "Value" "BAS16H-GP"
			(at 0 -5.5372 90)
			(unlocked yes)
			(layer "F.Fab")
			(hide yes)
			(effects
				(font
					(size 1.016 1.016)
					(thickness 0.1524)
				)
			)
		)
		(property "Device Type" "SOD123AKH48"
			(at 0 -7.0612 90)
			(unlocked yes)
			(layer "F.Fab")
			(hide yes)
			(effects
				(font
					(size 1.016 1.016)
					(thickness 0.1524)
				)
			)
		)
		(duplicate_pad_numbers_are_jumpers no)
		(fp_line
			(start 1.016 -2.667)
			(end -1.016 -2.667)
			(stroke
				(width 0.1524)
				(type default)
			)
			(layer "F.SilkS")
		)
		(fp_line
			(start -1.016 -2.667)
			(end -1.016 2.667)
			(stroke
				(width 0.1524)
				(type default)
			)
			(layer "F.SilkS")
		)
		(fp_line
			(start 1.016 2.667)
			(end 1.016 -2.667)
			(stroke
				(width 0.1524)
				(type default)
			)
			(layer "F.SilkS")
		)
		(fp_line
			(start -1.016 2.667)
			(end 1.016 2.667)
			(stroke
				(width 0.1524)
				(type default)
			)
			(layer "F.SilkS")
		)
		(fp_line
			(start 0.889 2.921)
			(end -0.889 2.921)
			(stroke
				(width 0.508)
				(type default)
			)
			(layer "F.SilkS")
		)
		(fp_rect
			(start -1.143 3.175)
			(end 1.143 -2.794)
			(stroke
				(width 0)
				(type default)
			)
			(fill no)
			(layer "F.CrtYd")
		)
		(fp_poly
			(pts
				(xy -1.143 -2.794) (xy 1.143 -2.794) (xy 1.143 3.175) (xy -1.143 3.175)
			)
			(stroke
				(width 0)
				(type default)
			)
			(fill no)
			(layer "F.Fab")
		)
		(pad "A" smd rect
			(at 0 -1.6891 90)
			(size 0.889 1.397)
			(layers "F.Cu" "F.Mask" "F.Paste")
			(net "FAN_TACH8")
		)
		(pad "K" smd rect
			(at 0 1.6891 90)
			(size 0.889 1.397)
			(layers "F.Cu" "F.Mask" "F.Paste")
			(net "P12V")
		)
	)
	(footprint ""
		(layer "F.Cu")
		(at 15.5702 -259.2324 -90)
		(property "Reference" "R88"
			(at 0 0 270)
			(layer "F.SilkS")
			(hide yes)
			(effects
				(font
					(size 1.27 1.27)
				)
			)
		)
		(property "Value" "10KR2F-2-GP"
			(at 0.064008 -3.993896 270)
			(unlocked yes)
			(layer "F.Fab")
			(hide yes)
			(effects
				(font
					(size 1.016 1.016)
					(thickness 0.1524)
				)
			)
		)
		(property "Device Type" "R402H16"
			(at 0.064008 -5.517896 270)
			(unlocked yes)
			(layer "F.Fab")
			(hide yes)
			(effects
				(font
					(size 1.016 1.016)
					(thickness 0.1524)
				)
			)
		)
		(duplicate_pad_numbers_are_jumpers no)
		(fp_line
			(start -0.508 -0.9398)
			(end -0.508 0.9398)
			(stroke
				(width 0.1524)
				(type default)
			)
			(layer "F.SilkS")
		)
		(fp_line
			(start 0.508 -0.9398)
			(end -0.508 -0.9398)
			(stroke
				(width 0.1524)
				(type default)
			)
			(layer "F.SilkS")
		)
		(fp_rect
			(start -0.508 0.9398)
			(end 0.508 -0.9398)
			(stroke
				(width 0)
				(type default)
			)
			(fill no)
			(layer "F.CrtYd")
		)
		(fp_rect
			(start -0.508 0.9398)
			(end 0.508 -0.9398)
			(stroke
				(width 0)
				(type default)
			)
			(fill no)
			(layer "F.Fab")
		)
		(pad "1" smd custom
			(at 0 -0.4445 270)
			(size 0.1397 0.1397)
			(layers "F.Cu" "F.Mask" "F.Paste")
			(net "FANIN_6")
			(options
				(clearance outline)
				(anchor circle)
			)
			(primitives
				(gr_poly
					(pts
						(arc
							(start -0.1778 -0.2794)
							(mid -0.249642 -0.249642)
							(end -0.2794 -0.1778)
						)
						(arc
							(start -0.2794 0.1778)
							(mid -0.249642 0.249642)
							(end -0.1778 0.2794)
						)
						(arc
							(start 0.1778 0.2794)
							(mid 0.249642 0.249642)
							(end 0.2794 0.1778)
						)
						(arc
							(start 0.2794 -0.1778)
							(mid 0.249642 -0.249642)
							(end 0.1778 -0.2794)
						)
					)
					(width 0)
					(fill yes)
				)
			)
		)
		(pad "2" smd custom
			(at 0 0.4445 270)
			(size 0.1397 0.1397)
			(layers "F.Cu" "F.Mask" "F.Paste")
			(net "GND")
			(options
				(clearance outline)
				(anchor circle)
			)
			(primitives
				(gr_poly
					(pts
						(arc
							(start -0.1778 -0.2794)
							(mid -0.249642 -0.249642)
							(end -0.2794 -0.1778)
						)
						(arc
							(start -0.2794 0.1778)
							(mid -0.249642 0.249642)
							(end -0.1778 0.2794)
						)
						(arc
							(start 0.1778 0.2794)
							(mid 0.249642 0.249642)
							(end 0.2794 0.1778)
						)
						(arc
							(start 0.2794 -0.1778)
							(mid 0.249642 -0.249642)
							(end 0.1778 -0.2794)
						)
					)
					(width 0)
					(fill yes)
				)
			)
		)
	)
	(footprint ""
		(layer "F.Cu")
		(at 43.9166 -106.2736 90)
		(property "Reference" "TC7"
			(at 0 0 90)
			(layer "F.SilkS")
			(hide yes)
			(effects
				(font
					(size 1.27 1.27)
				)
			)
		)
		(property "Value" "ST68U16VDM-1-GP"
			(at 0 -9.6012 90)
			(unlocked yes)
			(layer "F.Fab")
			(hide yes)
			(effects
				(font
					(size 1.016 1.016)
					(thickness 0.1524)
				)
			)
		)
		(property "Device Type" "CT7343H79"
			(at 0 -11.1252 90)
			(unlocked yes)
			(layer "F.Fab")
			(hide yes)
			(effects
				(font
					(size 1.016 1.016)
					(thickness 0.1524)
				)
			)
		)
		(duplicate_pad_numbers_are_jumpers no)
		(fp_line
			(start 2.286 -4.8768)
			(end -2.286 -4.8768)
			(stroke
				(width 0.1524)
				(type default)
			)
			(layer "F.SilkS")
		)
		(fp_line
			(start -2.286 -4.8768)
			(end -2.286 -2.032)
			(stroke
				(width 0.1524)
				(type default)
			)
			(layer "F.SilkS")
		)
		(fp_line
			(start 2.1082 -4.699)
			(end -2.1082 -4.699)
			(stroke
				(width 0.508)
				(type default)
			)
			(layer "F.SilkS")
		)
		(fp_line
			(start 2.286 -2.032)
			(end 2.286 -4.8768)
			(stroke
				(width 0.1524)
				(type default)
			)
			(layer "F.SilkS")
		)
		(fp_line
			(start 2.286 2.032)
			(end 2.286 4.8768)
			(stroke
				(width 0.1524)
				(type default)
			)
			(layer "F.SilkS")
		)
		(fp_line
			(start 2.286 4.8768)
			(end -2.286 4.8768)
			(stroke
				(width 0.1524)
				(type default)
			)
			(layer "F.SilkS")
		)
		(fp_line
			(start -2.286 4.8768)
			(end -2.286 2.032)
			(stroke
				(width 0.1524)
				(type default)
			)
			(layer "F.SilkS")
		)
		(fp_rect
			(start -2.1463 3.6449)
			(end 2.1463 -3.6449)
			(stroke
				(width 0)
				(type default)
			)
			(fill no)
			(layer "F.CrtYd")
		)
		(fp_poly
			(pts
				(xy -2.54 4.953) (xy -2.54 4.2926) (xy -3.81 4.2926) (xy -3.81 -4.2926) (xy -2.54 -4.2926) (xy -2.54 -4.953)
				(xy 2.54 -4.953) (xy 2.54 -4.2926) (xy 3.81 -4.2926) (xy 3.81 -1.6256) (xy 2.1463 -1.6256) (xy 2.1463 -3.6449)
				(xy -2.1463 -3.6449) (xy -2.1463 3.6449) (xy 2.1463 3.6449) (xy 2.1463 -1.6129) (xy 3.81 -1.6129)
				(xy 3.81 4.2926) (xy 2.54 4.2926) (xy 2.54 4.953)
			)
			(stroke
				(width 0)
				(type default)
			)
			(fill no)
			(layer "F.CrtYd")
		)
		(fp_rect
			(start 2.54 4.2926)
			(end 3.81 -4.2926)
			(stroke
				(width 0)
				(type default)
			)
			(fill no)
			(layer "F.Fab")
		)
		(fp_rect
			(start -3.81 4.2926)
			(end -2.54 -4.2926)
			(stroke
				(width 0)
				(type default)
			)
			(fill no)
			(layer "F.Fab")
		)
		(fp_rect
			(start -2.54 4.953)
			(end 2.54 -4.953)
			(stroke
				(width 0)
				(type default)
			)
			(fill no)
			(layer "F.Fab")
		)
		(pad "1" smd rect
			(at 0 -3.1496 90)
			(size 2.413 2.286)
			(layers "F.Cu" "F.Mask" "F.Paste")
			(net "P12VL")
		)
		(pad "2" smd rect
			(at 0 3.1496 90)
			(size 2.413 2.286)
			(layers "F.Cu" "F.Mask" "F.Paste")
			(net "GND")
		)
		(zone
			(layer "F.Cu")
			(hatch none 0.5)
			(connect_pads
				(clearance 0)
			)
			(min_thickness 0.25)
			(keepout
				(tracks allowed)
				(vias not_allowed)
				(pads allowed)
				(copperpour not_allowed)
				(footprints allowed)
			)
			(placement
				(enabled no)
				(sheetname "")
			)
			(fill
				(thermal_gap 0.5)
				(thermal_bridge_width 0.5)
				(island_removal_mode 0)
			)
			(polygon
				(pts
					(xy 42.2275 -107.7849) (xy 39.3192 -107.7849) (xy 39.3192 -104.7623) (xy 42.2148 -104.7623) (xy 42.545 -104.7623)
					(xy 42.545 -107.7849)
				)
			)
		)
		(zone
			(layer "F.Cu")
			(hatch none 0.5)
			(connect_pads
				(clearance 0)
			)
			(min_thickness 0.25)
			(keepout
				(tracks allowed)
				(vias not_allowed)
				(pads allowed)
				(copperpour not_allowed)
				(footprints allowed)
			)
			(placement
				(enabled no)
				(sheetname "")
			)
			(fill
				(thermal_gap 0.5)
				(thermal_bridge_width 0.5)
				(island_removal_mode 0)
			)
			(polygon
				(pts
					(xy 48.514 -104.7623) (xy 48.514 -107.7849) (xy 45.6184 -107.7849) (xy 45.2882 -107.7849) (xy 45.2882 -104.7623)
					(xy 45.6184 -104.7623)
				)
			)
		)
	)
	(footprint ""
		(layer "F.Cu")
		(at 21.766784 -215.519 90)
		(property "Reference" "R131"
			(at 0 0 90)
			(layer "F.SilkS")
			(hide yes)
			(effects
				(font
					(size 1.27 1.27)
				)
			)
		)
		(property "Value" "4K7R2F-GP"
			(at 0.064008 -3.993896 90)
			(unlocked yes)
			(layer "F.Fab")
			(hide yes)
			(effects
				(font
					(size 1.016 1.016)
					(thickness 0.1524)
				)
			)
		)
		(property "Device Type" "R402H16"
			(at 0.064008 -5.517896 90)
			(unlocked yes)
			(layer "F.Fab")
			(hide yes)
			(effects
				(font
					(size 1.016 1.016)
					(thickness 0.1524)
				)
			)
		)
		(duplicate_pad_numbers_are_jumpers no)
		(fp_line
			(start 0.508 -0.9398)
			(end -0.508 -0.9398)
			(stroke
				(width 0.1524)
				(type default)
			)
			(layer "F.SilkS")
		)
		(fp_line
			(start -0.508 -0.9398)
			(end -0.508 0.9398)
			(stroke
				(width 0.1524)
				(type default)
			)
			(layer "F.SilkS")
		)
		(fp_rect
			(start -0.508 0.9398)
			(end 0.508 -0.9398)
			(stroke
				(width 0)
				(type default)
			)
			(fill no)
			(layer "F.CrtYd")
		)
		(fp_rect
			(start -0.508 0.9398)
			(end 0.508 -0.9398)
			(stroke
				(width 0)
				(type default)
			)
			(fill no)
			(layer "F.Fab")
		)
		(pad "1" smd custom
			(at 0 -0.4445 90)
			(size 0.1397 0.1397)
			(layers "F.Cu" "F.Mask" "F.Paste")
			(net "P3V3")
			(options
				(clearance outline)
				(anchor circle)
			)
			(primitives
				(gr_poly
					(pts
						(arc
							(start -0.1778 -0.2794)
							(mid -0.249642 -0.249642)
							(end -0.2794 -0.1778)
						)
						(arc
							(start -0.2794 0.1778)
							(mid -0.249642 0.249642)
							(end -0.1778 0.2794)
						)
						(arc
							(start 0.1778 0.2794)
							(mid 0.249642 0.249642)
							(end 0.2794 0.1778)
						)
						(arc
							(start 0.2794 -0.1778)
							(mid 0.249642 -0.249642)
							(end 0.1778 -0.2794)
						)
					)
					(width 0)
					(fill yes)
				)
			)
		)
		(pad "2" smd custom
			(at 0 0.4445 90)
			(size 0.1397 0.1397)
			(layers "F.Cu" "F.Mask" "F.Paste")
			(net "PWM_OUT_FAN5")
			(options
				(clearance outline)
				(anchor circle)
			)
			(primitives
				(gr_poly
					(pts
						(arc
							(start -0.1778 -0.2794)
							(mid -0.249642 -0.249642)
							(end -0.2794 -0.1778)
						)
						(arc
							(start -0.2794 0.1778)
							(mid -0.249642 0.249642)
							(end -0.1778 0.2794)
						)
						(arc
							(start 0.1778 0.2794)
							(mid 0.249642 0.249642)
							(end 0.2794 0.1778)
						)
						(arc
							(start 0.2794 -0.1778)
							(mid 0.249642 -0.249642)
							(end 0.1778 -0.2794)
						)
					)
					(width 0)
					(fill yes)
				)
			)
		)
	)
	(footprint ""
		(layer "F.Cu")
		(at 16.2814 -231.4194)
		(property "Reference" "R115"
			(at 0 0 0)
			(layer "F.SilkS")
			(hide yes)
			(effects
				(font
					(size 1.27 1.27)
				)
			)
		)
		(property "Value" "2KR2F-3-GP"
			(at 0.064008 -3.993896 0)
			(unlocked yes)
			(layer "F.Fab")
			(hide yes)
			(effects
				(font
					(size 1.016 1.016)
					(thickness 0.1524)
				)
			)
		)
		(property "Device Type" "R402H16"
			(at 0.064008 -5.517896 0)
			(unlocked yes)
			(layer "F.Fab")
			(hide yes)
			(effects
				(font
					(size 1.016 1.016)
					(thickness 0.1524)
				)
			)
		)
		(duplicate_pad_numbers_are_jumpers no)
		(fp_line
			(start -0.508 -0.9398)
			(end -0.508 0.9398)
			(stroke
				(width 0.1524)
				(type default)
			)
			(layer "F.SilkS")
		)
		(fp_line
			(start 0.508 -0.9398)
			(end -0.508 -0.9398)
			(stroke
				(width 0.1524)
				(type default)
			)
			(layer "F.SilkS")
		)
		(fp_rect
			(start -0.508 0.9398)
			(end 0.508 -0.9398)
			(stroke
				(width 0)
				(type default)
			)
			(fill no)
			(layer "F.CrtYd")
		)
		(fp_rect
			(start -0.508 0.9398)
			(end 0.508 -0.9398)
			(stroke
				(width 0)
				(type default)
			)
			(fill no)
			(layer "F.Fab")
		)
		(pad "1" smd custom
			(at 0 -0.4445)
			(size 0.1397 0.1397)
			(layers "F.Cu" "F.Mask" "F.Paste")
			(net "LED_DR_LED3")
			(options
				(clearance outline)
				(anchor circle)
			)
			(primitives
				(gr_poly
					(pts
						(arc
							(start -0.1778 -0.2794)
							(mid -0.249642 -0.249642)
							(end -0.2794 -0.1778)
						)
						(arc
							(start -0.2794 0.1778)
							(mid -0.249642 0.249642)
							(end -0.1778 0.2794)
						)
						(arc
							(start 0.1778 0.2794)
							(mid 0.249642 0.249642)
							(end 0.2794 0.1778)
						)
						(arc
							(start 0.2794 -0.1778)
							(mid 0.249642 -0.249642)
							(end 0.1778 -0.2794)
						)
					)
					(width 0)
					(fill yes)
				)
			)
		)
		(pad "2" smd custom
			(at 0 0.4445)
			(size 0.1397 0.1397)
			(layers "F.Cu" "F.Mask" "F.Paste")
			(net "LED_DR_LED3_B")
			(options
				(clearance outline)
				(anchor circle)
			)
			(primitives
				(gr_poly
					(pts
						(arc
							(start -0.1778 -0.2794)
							(mid -0.249642 -0.249642)
							(end -0.2794 -0.1778)
						)
						(arc
							(start -0.2794 0.1778)
							(mid -0.249642 0.249642)
							(end -0.1778 0.2794)
						)
						(arc
							(start 0.1778 0.2794)
							(mid 0.249642 0.249642)
							(end 0.2794 0.1778)
						)
						(arc
							(start 0.2794 -0.1778)
							(mid 0.249642 -0.249642)
							(end 0.1778 -0.2794)
						)
					)
					(width 0)
					(fill yes)
				)
			)
		)
	)
)
